FILE_TYPE = CONNECTIVITY;
{Allegro Design Entry HDL 16.6-p007 (v16-6-112F) 10/10/2012}
"PAGE_NUMBER" = 63;
0"NC";
1"PVCCMCP_CPU1\g";
2"TP_RST_CPU1_CD_HFI0_N";
3"TP_FM_CPU1_CD_HFI0_MODPRST_N";
4"TP_LED_CPU1_CD_HFI0_N";
5"TP_IRQ_CPU1_CD_HFI0_N";
6"TP_SMB_CPU1_CD_HFI0_I2CDAT";
7"TP_SMB_CPU1_CD_HFI0_I2CCLK";
8"JTAG_MCP_TMS";
9"JTAG_MCP_TCK";
10"CLK_156M_OSC_CPU1_HFI_DP";
11"CLK_156M_OSC_CPU1_HFI_DN";
12"JTAG_MCP_TRST_N";
13"JTAG_MCP_CPU1_TDI";
14"TP_CPU1_RSVD_174";
15"TP_CPU1_RSVD_175";
16"TP_CPU1_RSVD_176";
17"TP_CPU1_RSVD_177";
18"TP_CPU1_RSVD_178";
19"TP_CPU1_RSVD_179";
20"TP_CPU1_RSVD_180";
21"TP_CPU1_RSVD_181";
22"TP_CPU1_DMI_RX_DP0";
23"TP_CPU1_DMI_RX_DP1";
24"TP_CPU1_DMI_RX_DP2";
25"TP_CPU1_DMI_RX_DP3";
26"TP_CPU1_DMI_RX_DN0";
27"TP_CPU1_DMI_RX_DN1";
28"TP_CPU1_DMI_RX_DN2";
29"TP_CPU1_DMI_RX_DN3";
30"TP_CPU1_RSVD_182";
31"TP_CPU1_RSVD_183";
32"TP_CPU1_RSVD_172";
33"TP_CPU1_RSVD_173";
34"TP_CPU1_RSVD_184";
35"TP_CPU1_RSVD_186";
36"TP_CPU1_RSVD_190";
37"TP_CPU1_RSVD_189";
38"TP_CPU1_DMI_TX_DP0";
39"TP_CPU1_DMI_TX_DP1";
40"TP_CPU1_DMI_TX_DP2";
41"TP_CPU1_DMI_TX_DP3";
42"TP_CPU1_DMI_TX_DN0";
43"TP_CPU1_DMI_TX_DN1";
44"TP_CPU1_DMI_TX_DN2";
45"TP_CPU1_DMI_TX_DN3";
46"CLK_100M_CPU1_PE_REFCLK_DP";
47"CLK_100M_CPU1_PE_REFCLK_DN";
48"RST_CD_CPU1_POR_N";
49"JTAG_MCP_CPU1_TDO";
50"TP_CD_HFI1_CPU1_RESET_N";
51"TP_CD_HFI1_CPU1_MODPRST_N";
52"TP_CD_HFI1_CPU1_LED_N";
53"TP_CD_HFI1_CPU1_INT_N";
54"TP_CD_HFI1_CPU1_I2CDAT";
55"TP_CD_HFI1_CPU1_I2CLK";
%"SKX_EXT_B"
"9","(-4075,2500)","0","chpset_lib","I23";
;
CDS_SEC"9"
CDS_LOCATION"U2D1"
SEC"9"
CDS_LIB"chpset_lib"
SEC_TYPE"BGA1"
PACK_TYPE"BGA1"
MATERIAL"IC"
PART_NUMBER"TBD"
LOCATION"U2D1";
"RSVD<172>"
$PN"BA76"32;
"RSVD<173>"
$PN"BA66"33;
"RSVD<174>"
$PN"BA64"14;
"RSVD<175>"
$PN"BA22"15;
"RSVD<176>"
$PN"BA18"16;
"RSVD<177>"
$PN"BA16"17;
"RSVD<178>"
$PN"BA14"18;
"RSVD<179>"
$PN"AY77"19;
"RSVD<180>"
$PN"AY75"20;
"RSVD<181>"
$PN"AY67"21;
"RSVD<182>"
$PN"AY65"30;
"RSVD<183>"
$PN"AW76"31;
"RSVD<184>"
$PN"AW64"34;
"RSVD<186>"
$PN"AV77"35;
"RSVD<187>"
$PN"AT25"1;
"RSVD<188>"
$PN"AT23"1;
"RSVD<189>"
$PN"AT13"37;
"RSVD<190>"
$PN"AR62"36;
"RSVD<191>"
$PN"AR26"1;
"RSVD<192>"
$PN"AR22"1;
"RSVD<193>"
$PN"AR20"1;
"DMI_TX_DP<0>"
$PN"CH5"38;
"DMI_TX_DP<1>"
$PN"CL4"39;
"DMI_TX_DP<2>"
$PN"CM3"40;
"DMI_TX_DP<3>"
$PN"CR4"41;
"DMI_TX_DN<0>"
$PN"CG4"42;
"DMI_TX_DN<1>"
$PN"CJ4"43;
"DMI_TX_DN<2>"
$PN"CN4"44;
"DMI_TX_DN<3>"
$PN"CP5"45;
"DMI_RX_DP<0>"
$PN"CL10"22;
"DMI_RX_DP<1>"
$PN"CN10"23;
"DMI_RX_DP<2>"
$PN"CP11"24;
"DMI_RX_DP<3>"
$PN"CV11"25;
"DMI_RX_DN<0>"
$PN"CK9"26;
"DMI_RX_DN<1>"
$PN"CM11"27;
"DMI_RX_DN<2>"
$PN"CR12"28;
"DMI_RX_DN<3>"
$PN"CT11"29;
"CD_TRST_N"
$PN"CD23"12;
"CD_TMS"
$PN"CE24"8;
"CD_TDO"
$PN"CC22"49;
"CD_TDI"
$PN"BY21"13;
"CD_TCLK"
$PN"CB23"9;
"CD_POR_N"
$PN"CF25"48;
"CD_PE_REFCLK_DP"
$PN"BW24"46;
"CD_PE_REFCLK_DN"
$PN"BU24"47;
"CD_HFI_REFCLK_DP"
$PN"BG16"10;
"CD_HFI_REFCLK_DN"
$PN"BE16"11;
"CD_HFI1_RESET_N"
$PN"BK23"50;
"CD_HFI1_MODPRST_N"
$PN"BT19"51;
"CD_HFI1_LED_N"
$PN"BM23"52;
"CD_HFI1_INT_N"
$PN"BM21"53;
"CD_HFI1_I2CDAT"
$PN"BH23"54;
"CD_HFI1_I2CCLK"
$PN"BJ22"55;
"CD_HFI0_RESET_N"
$PN"BN24"2;
"CD_HFI0_MODPRST_N"
$PN"BR20"3;
"CD_HFI0_LED_N"
$PN"BK21"4;
"CD_HFI0_INT_N"
$PN"BP19"5;
"CD_HFI0_I2CDAT"
$PN"BP23"6;
"CD_HFI0_I2CCLK"
$PN"BN22"7;
%"VCC_CORE"
"1","(-1425,2250)","0","mstr_symbols","I27";
;
CDS_LIB"mstr_symbols"
HDL_POWER"PVCCMCP_CPU1";
"A"1;
END.
